(kicad_pcb
	(version 20260206)
	(generator "pcbnew")
	(generator_version "10.0")
	(general
		(thickness 1.6)
		(legacy_teardrops no)
	)
	(paper "A4")
	(title_block
		(title "12092022_DA0F0TMDCD0_F0T_Management_Board_D_brd_V3_OCP.brd")
		(comment 1 "Grand Teton / footprints 174-179 of 1440")
	)
	(layers
		(0 "F.Cu" signal "TOP")
		(4 "In1.Cu" signal "GND")
		(6 "In2.Cu" signal "IN1")
		(8 "In3.Cu" signal "GND1")
		(10 "In4.Cu" signal "IN2")
		(12 "In5.Cu" signal "VCC")
		(14 "In6.Cu" signal "VCC1")
		(16 "In7.Cu" signal "IN3")
		(18 "In8.Cu" signal "GND2")
		(20 "In9.Cu" signal "IN4")
		(22 "In10.Cu" signal "GND3")
		(2 "B.Cu" signal "BOTTOM")
		(9 "F.Adhes" user "F.Adhesive")
		(11 "B.Adhes" user "B.Adhesive")
		(13 "F.Paste" user "Package Geometry/Pastemask Top")
		(15 "B.Paste" user "Package Geometry/Pastemask Bottom")
		(5 "F.SilkS" user "Ref Des/Silkscreen Top")
		(7 "B.SilkS" user "Ref Des/Silkscreen Bottom")
		(1 "F.Mask" user "Board Geometry/Soldermask Top")
		(3 "B.Mask" user "Board Geometry/Soldermask Bottom")
		(17 "Dwgs.User" user "User.Drawings")
		(19 "Cmts.User" user "User.Comments")
		(21 "Eco1.User" user "User.Eco1")
		(23 "Eco2.User" user "User.Eco2")
		(25 "Edge.Cuts" user "Board Geometry/Outline")
		(27 "Margin" user)
		(31 "F.CrtYd" user "Package Geometry/Place Bound Top")
		(29 "B.CrtYd" user "Package Geometry/Place Bound Bottom")
		(35 "F.Fab" user "Ref Des/Assembly Top")
		(33 "B.Fab" user "Ref Des/Assembly Bottom")
	)
	(footprint ""
		(layer "F.Cu")
		(at 32.131 -64.8208 90)
		(property "Reference" "C310"
			(at 0 0 90)
			(layer "F.SilkS")
			(hide yes)
			(effects
				(font
					(size 1.27 1.27)
				)
			)
		)
		(property "Value" ""
			(at 0 0 90)
			(layer "F.Fab")
			(effects
				(font
					(size 1.27 1.27)
				)
			)
		)
		(duplicate_pad_numbers_are_jumpers no)
		(fp_line
			(start 0.7874 -0.4064)
			(end 0.7874 0.4064)
			(stroke
				(width 0.1524)
				(type default)
			)
			(layer "F.SilkS")
		)
		(fp_line
			(start -0.7874 -0.4064)
			(end 0.7874 -0.4064)
			(stroke
				(width 0.1524)
				(type default)
			)
			(layer "F.SilkS")
		)
		(fp_line
			(start 0.7874 0.4064)
			(end -0.7874 0.4064)
			(stroke
				(width 0.1524)
				(type default)
			)
			(layer "F.SilkS")
		)
		(fp_line
			(start -0.7874 0.4064)
			(end -0.7874 -0.4064)
			(stroke
				(width 0.1524)
				(type default)
			)
			(layer "F.SilkS")
		)
		(fp_line
			(start -0.12065 -0.305054)
			(end -0.12065 -0.2794)
			(stroke
				(width 0.1)
				(type default)
			)
			(layer "F.Fab")
		)
		(fp_line
			(start -0.67945 -0.305054)
			(end -0.12065 -0.305054)
			(stroke
				(width 0.1)
				(type default)
			)
			(layer "F.Fab")
		)
		(fp_line
			(start 0.67945 -0.3048)
			(end 0.67945 0.3048)
			(stroke
				(width 0.1)
				(type default)
			)
			(layer "F.Fab")
		)
		(fp_line
			(start 0.12065 -0.3048)
			(end 0.67945 -0.3048)
			(stroke
				(width 0.1)
				(type default)
			)
			(layer "F.Fab")
		)
		(fp_line
			(start 0.12065 -0.2794)
			(end 0.12065 -0.3048)
			(stroke
				(width 0.1)
				(type default)
			)
			(layer "F.Fab")
		)
		(fp_line
			(start -0.12065 -0.2794)
			(end 0.12065 -0.2794)
			(stroke
				(width 0.1)
				(type default)
			)
			(layer "F.Fab")
		)
		(fp_line
			(start 0.120396 0.2794)
			(end -0.12065 0.2794)
			(stroke
				(width 0.1)
				(type default)
			)
			(layer "F.Fab")
		)
		(fp_line
			(start -0.12065 0.2794)
			(end -0.12065 0.3048)
			(stroke
				(width 0.1)
				(type default)
			)
			(layer "F.Fab")
		)
		(fp_line
			(start 0.67945 0.3048)
			(end 0.120396 0.3048)
			(stroke
				(width 0.1)
				(type default)
			)
			(layer "F.Fab")
		)
		(fp_line
			(start 0.120396 0.3048)
			(end 0.120396 0.2794)
			(stroke
				(width 0.1)
				(type default)
			)
			(layer "F.Fab")
		)
		(fp_line
			(start -0.12065 0.3048)
			(end -0.67945 0.3048)
			(stroke
				(width 0.1)
				(type default)
			)
			(layer "F.Fab")
		)
		(fp_line
			(start -0.67945 0.3048)
			(end -0.67945 -0.305054)
			(stroke
				(width 0.1)
				(type default)
			)
			(layer "F.Fab")
		)
		(pad "1" smd circle
			(at -0.40005 0 90)
			(size 0 0)
			(layers "F.Cu" "F.Mask" "F.Paste")
			(net "PWRGD_P3V3_RGM_R2")
		)
		(pad "2" smd circle
			(at 0.40005 0 90)
			(size 0 0)
			(layers "F.Cu" "F.Mask" "F.Paste")
			(net "GND")
		)
	)
	(footprint ""
		(layer "F.Cu")
		(at 4.953 -31.837122 -90)
		(property "Reference" "PC215"
			(at 0 0 270)
			(layer "F.SilkS")
			(hide yes)
			(effects
				(font
					(size 1.27 1.27)
				)
			)
		)
		(property "Value" ""
			(at 0 0 270)
			(layer "F.Fab")
			(effects
				(font
					(size 1.27 1.27)
				)
			)
		)
		(duplicate_pad_numbers_are_jumpers no)
		(fp_line
			(start -1.651 0.8382)
			(end -1.651 -0.8382)
			(stroke
				(width 0.1524)
				(type default)
			)
			(layer "F.SilkS")
		)
		(fp_line
			(start 0 0.8382)
			(end 0 -0.8382)
			(stroke
				(width 0.1524)
				(type default)
			)
			(layer "F.SilkS")
		)
		(fp_line
			(start 1.651 0.8382)
			(end -1.651 0.8382)
			(stroke
				(width 0.1524)
				(type default)
			)
			(layer "F.SilkS")
		)
		(fp_line
			(start -1.651 -0.8382)
			(end 1.651 -0.8382)
			(stroke
				(width 0.1524)
				(type default)
			)
			(layer "F.SilkS")
		)
		(fp_line
			(start 1.651 -0.8382)
			(end 1.651 0.8382)
			(stroke
				(width 0.1524)
				(type default)
			)
			(layer "F.SilkS")
		)
		(fp_line
			(start -1.55956 0.7366)
			(end -1.524 0.7366)
			(stroke
				(width 0.1)
				(type default)
			)
			(layer "F.Fab")
		)
		(fp_line
			(start -1.524 0.7366)
			(end 1.524 0.7366)
			(stroke
				(width 0.1)
				(type default)
			)
			(layer "F.Fab")
		)
		(fp_line
			(start 1.524 0.7366)
			(end 1.55956 0.7366)
			(stroke
				(width 0.1)
				(type default)
			)
			(layer "F.Fab")
		)
		(fp_line
			(start 1.55956 0.7366)
			(end 1.55956 -0.7366)
			(stroke
				(width 0.1)
				(type default)
			)
			(layer "F.Fab")
		)
		(fp_line
			(start -1.55956 -0.7366)
			(end -1.55956 0.7366)
			(stroke
				(width 0.1)
				(type default)
			)
			(layer "F.Fab")
		)
		(fp_line
			(start -1.524 -0.7366)
			(end -1.55956 -0.7366)
			(stroke
				(width 0.1)
				(type default)
			)
			(layer "F.Fab")
		)
		(fp_line
			(start 1.524 -0.7366)
			(end -1.524 -0.7366)
			(stroke
				(width 0.1)
				(type default)
			)
			(layer "F.Fab")
		)
		(fp_line
			(start 1.55956 -0.7366)
			(end 1.524 -0.7366)
			(stroke
				(width 0.1)
				(type default)
			)
			(layer "F.Fab")
		)
		(pad "1" smd rect
			(at -0.94996 0 90)
			(size 1.1176 1.3716)
			(layers "F.Cu" "F.Mask" "F.Paste")
			(net "P5V_AUX")
		)
		(pad "2" smd rect
			(at 0.94996 0 90)
			(size 1.1176 1.3716)
			(layers "F.Cu" "F.Mask" "F.Paste")
			(net "GND")
		)
	)
	(footprint ""
		(layer "F.Cu")
		(at 11.147044 -48.64989)
		(property "Reference" "PC271"
			(at 0 0 0)
			(layer "F.SilkS")
			(hide yes)
			(effects
				(font
					(size 1.27 1.27)
				)
			)
		)
		(property "Value" ""
			(at 0 0 0)
			(layer "F.Fab")
			(effects
				(font
					(size 1.27 1.27)
				)
			)
		)
		(duplicate_pad_numbers_are_jumpers no)
		(fp_line
			(start -0.7874 -0.4064)
			(end 0.7874 -0.4064)
			(stroke
				(width 0.1524)
				(type default)
			)
			(layer "F.SilkS")
		)
		(fp_line
			(start -0.7874 0.4064)
			(end -0.7874 -0.4064)
			(stroke
				(width 0.1524)
				(type default)
			)
			(layer "F.SilkS")
		)
		(fp_line
			(start 0.7874 -0.4064)
			(end 0.7874 0.4064)
			(stroke
				(width 0.1524)
				(type default)
			)
			(layer "F.SilkS")
		)
		(fp_line
			(start 0.7874 0.4064)
			(end -0.7874 0.4064)
			(stroke
				(width 0.1524)
				(type default)
			)
			(layer "F.SilkS")
		)
		(fp_line
			(start -0.67945 -0.305054)
			(end -0.12065 -0.305054)
			(stroke
				(width 0.1)
				(type default)
			)
			(layer "F.Fab")
		)
		(fp_line
			(start -0.67945 0.3048)
			(end -0.67945 -0.305054)
			(stroke
				(width 0.1)
				(type default)
			)
			(layer "F.Fab")
		)
		(fp_line
			(start -0.12065 -0.305054)
			(end -0.12065 -0.2794)
			(stroke
				(width 0.1)
				(type default)
			)
			(layer "F.Fab")
		)
		(fp_line
			(start -0.12065 -0.2794)
			(end 0.12065 -0.2794)
			(stroke
				(width 0.1)
				(type default)
			)
			(layer "F.Fab")
		)
		(fp_line
			(start -0.12065 0.2794)
			(end -0.12065 0.3048)
			(stroke
				(width 0.1)
				(type default)
			)
			(layer "F.Fab")
		)
		(fp_line
			(start -0.12065 0.3048)
			(end -0.67945 0.3048)
			(stroke
				(width 0.1)
				(type default)
			)
			(layer "F.Fab")
		)
		(fp_line
			(start 0.120396 0.2794)
			(end -0.12065 0.2794)
			(stroke
				(width 0.1)
				(type default)
			)
			(layer "F.Fab")
		)
		(fp_line
			(start 0.120396 0.3048)
			(end 0.120396 0.2794)
			(stroke
				(width 0.1)
				(type default)
			)
			(layer "F.Fab")
		)
		(fp_line
			(start 0.12065 -0.3048)
			(end 0.67945 -0.3048)
			(stroke
				(width 0.1)
				(type default)
			)
			(layer "F.Fab")
		)
		(fp_line
			(start 0.12065 -0.2794)
			(end 0.12065 -0.3048)
			(stroke
				(width 0.1)
				(type default)
			)
			(layer "F.Fab")
		)
		(fp_line
			(start 0.67945 -0.3048)
			(end 0.67945 0.3048)
			(stroke
				(width 0.1)
				(type default)
			)
			(layer "F.Fab")
		)
		(fp_line
			(start 0.67945 0.3048)
			(end 0.120396 0.3048)
			(stroke
				(width 0.1)
				(type default)
			)
			(layer "F.Fab")
		)
		(pad "1" smd circle
			(at -0.40005 0)
			(size 0 0)
			(layers "F.Cu" "F.Mask" "F.Paste")
			(net "P5V_AUX_REF")
		)
		(pad "2" smd circle
			(at 0.40005 0)
			(size 0 0)
			(layers "F.Cu" "F.Mask" "F.Paste")
			(net "GND")
		)
	)
	(footprint ""
		(layer "F.Cu")
		(at 28.2194 -70.5358 90)
		(property "Reference" "R867"
			(at 0 0 90)
			(layer "F.SilkS")
			(hide yes)
			(effects
				(font
					(size 1.27 1.27)
				)
			)
		)
		(property "Value" ""
			(at 0 0 90)
			(layer "F.Fab")
			(effects
				(font
					(size 1.27 1.27)
				)
			)
		)
		(duplicate_pad_numbers_are_jumpers no)
		(fp_line
			(start 0.7874 -0.4064)
			(end 0.7874 0.4064)
			(stroke
				(width 0.1524)
				(type default)
			)
			(layer "F.SilkS")
		)
		(fp_line
			(start -0.7874 -0.4064)
			(end 0.7874 -0.4064)
			(stroke
				(width 0.1524)
				(type default)
			)
			(layer "F.SilkS")
		)
		(fp_line
			(start 0.7874 0.4064)
			(end -0.7874 0.4064)
			(stroke
				(width 0.1524)
				(type default)
			)
			(layer "F.SilkS")
		)
		(fp_line
			(start -0.7874 0.4064)
			(end -0.7874 -0.4064)
			(stroke
				(width 0.1524)
				(type default)
			)
			(layer "F.SilkS")
		)
		(fp_line
			(start -0.12065 -0.305054)
			(end -0.12065 -0.2794)
			(stroke
				(width 0.1)
				(type default)
			)
			(layer "F.Fab")
		)
		(fp_line
			(start -0.67945 -0.305054)
			(end -0.12065 -0.305054)
			(stroke
				(width 0.1)
				(type default)
			)
			(layer "F.Fab")
		)
		(fp_line
			(start 0.67945 -0.3048)
			(end 0.67945 0.3048)
			(stroke
				(width 0.1)
				(type default)
			)
			(layer "F.Fab")
		)
		(fp_line
			(start 0.12065 -0.3048)
			(end 0.67945 -0.3048)
			(stroke
				(width 0.1)
				(type default)
			)
			(layer "F.Fab")
		)
		(fp_line
			(start 0.12065 -0.2794)
			(end 0.12065 -0.3048)
			(stroke
				(width 0.1)
				(type default)
			)
			(layer "F.Fab")
		)
		(fp_line
			(start -0.12065 -0.2794)
			(end 0.12065 -0.2794)
			(stroke
				(width 0.1)
				(type default)
			)
			(layer "F.Fab")
		)
		(fp_line
			(start 0.120396 0.2794)
			(end -0.12065 0.2794)
			(stroke
				(width 0.1)
				(type default)
			)
			(layer "F.Fab")
		)
		(fp_line
			(start -0.12065 0.2794)
			(end -0.12065 0.3048)
			(stroke
				(width 0.1)
				(type default)
			)
			(layer "F.Fab")
		)
		(fp_line
			(start 0.67945 0.3048)
			(end 0.120396 0.3048)
			(stroke
				(width 0.1)
				(type default)
			)
			(layer "F.Fab")
		)
		(fp_line
			(start 0.120396 0.3048)
			(end 0.120396 0.2794)
			(stroke
				(width 0.1)
				(type default)
			)
			(layer "F.Fab")
		)
		(fp_line
			(start -0.12065 0.3048)
			(end -0.67945 0.3048)
			(stroke
				(width 0.1)
				(type default)
			)
			(layer "F.Fab")
		)
		(fp_line
			(start -0.67945 0.3048)
			(end -0.67945 -0.305054)
			(stroke
				(width 0.1)
				(type default)
			)
			(layer "F.Fab")
		)
		(pad "1" smd circle
			(at -0.40005 0 90)
			(size 0 0)
			(layers "F.Cu" "F.Mask" "F.Paste")
			(net "P3V3_AUX")
		)
		(pad "2" smd circle
			(at 0.40005 0 90)
			(size 0 0)
			(layers "F.Cu" "F.Mask" "F.Paste")
			(net "EMMC_WP")
		)
	)
	(footprint ""
		(layer "F.Cu")
		(at 28.575 -10.287 90)
		(property "Reference" "C324"
			(at 0 0 90)
			(layer "F.SilkS")
			(hide yes)
			(effects
				(font
					(size 1.27 1.27)
				)
			)
		)
		(property "Value" ""
			(at 0 0 90)
			(layer "F.Fab")
			(effects
				(font
					(size 1.27 1.27)
				)
			)
		)
		(duplicate_pad_numbers_are_jumpers no)
		(fp_line
			(start 0.7874 -0.4064)
			(end 0.7874 0.4064)
			(stroke
				(width 0.1524)
				(type default)
			)
			(layer "F.SilkS")
		)
		(fp_line
			(start -0.7874 -0.4064)
			(end 0.7874 -0.4064)
			(stroke
				(width 0.1524)
				(type default)
			)
			(layer "F.SilkS")
		)
		(fp_line
			(start 0.7874 0.4064)
			(end -0.7874 0.4064)
			(stroke
				(width 0.1524)
				(type default)
			)
			(layer "F.SilkS")
		)
		(fp_line
			(start -0.7874 0.4064)
			(end -0.7874 -0.4064)
			(stroke
				(width 0.1524)
				(type default)
			)
			(layer "F.SilkS")
		)
		(fp_line
			(start -0.12065 -0.305054)
			(end -0.12065 -0.2794)
			(stroke
				(width 0.1)
				(type default)
			)
			(layer "F.Fab")
		)
		(fp_line
			(start -0.67945 -0.305054)
			(end -0.12065 -0.305054)
			(stroke
				(width 0.1)
				(type default)
			)
			(layer "F.Fab")
		)
		(fp_line
			(start 0.67945 -0.3048)
			(end 0.67945 0.3048)
			(stroke
				(width 0.1)
				(type default)
			)
			(layer "F.Fab")
		)
		(fp_line
			(start 0.12065 -0.3048)
			(end 0.67945 -0.3048)
			(stroke
				(width 0.1)
				(type default)
			)
			(layer "F.Fab")
		)
		(fp_line
			(start 0.12065 -0.2794)
			(end 0.12065 -0.3048)
			(stroke
				(width 0.1)
				(type default)
			)
			(layer "F.Fab")
		)
		(fp_line
			(start -0.12065 -0.2794)
			(end 0.12065 -0.2794)
			(stroke
				(width 0.1)
				(type default)
			)
			(layer "F.Fab")
		)
		(fp_line
			(start 0.120396 0.2794)
			(end -0.12065 0.2794)
			(stroke
				(width 0.1)
				(type default)
			)
			(layer "F.Fab")
		)
		(fp_line
			(start -0.12065 0.2794)
			(end -0.12065 0.3048)
			(stroke
				(width 0.1)
				(type default)
			)
			(layer "F.Fab")
		)
		(fp_line
			(start 0.67945 0.3048)
			(end 0.120396 0.3048)
			(stroke
				(width 0.1)
				(type default)
			)
			(layer "F.Fab")
		)
		(fp_line
			(start 0.120396 0.3048)
			(end 0.120396 0.2794)
			(stroke
				(width 0.1)
				(type default)
			)
			(layer "F.Fab")
		)
		(fp_line
			(start -0.12065 0.3048)
			(end -0.67945 0.3048)
			(stroke
				(width 0.1)
				(type default)
			)
			(layer "F.Fab")
		)
		(fp_line
			(start -0.67945 0.3048)
			(end -0.67945 -0.305054)
			(stroke
				(width 0.1)
				(type default)
			)
			(layer "F.Fab")
		)
		(pad "1" smd circle
			(at -0.40005 0 90)
			(size 0 0)
			(layers "F.Cu" "F.Mask" "F.Paste")
			(net "HDD_LED_BUF_R")
		)
		(pad "2" smd circle
			(at 0.40005 0 90)
			(size 0 0)
			(layers "F.Cu" "F.Mask" "F.Paste")
			(net "GND")
		)
	)
	(footprint ""
		(layer "F.Cu")
		(at 81.744058 -72.680576 -90)
		(property "Reference" "PU41"
			(at -3.61823 5.860034 0)
			(unlocked yes)
			(layer "F.SilkS")
			(effects
				(font
					(size 0.7874 0.5842)
					(thickness 0.1524)
				)
				(justify left)
			)
		)
		(property "Value" ""
			(at 0 0 270)
			(layer "F.Fab")
			(effects
				(font
					(size 1.27 1.27)
				)
			)
		)
		(duplicate_pad_numbers_are_jumpers no)
		(fp_line
			(start -1.050036 1.549908)
			(end -1.016 1.549908)
			(stroke
				(width 0.1524)
				(type default)
			)
			(layer "F.SilkS")
		)
		(fp_line
			(start 1.016 1.549908)
			(end 1.050036 1.549908)
			(stroke
				(width 0.1524)
				(type default)
			)
			(layer "F.SilkS")
		)
		(fp_line
			(start 1.050036 1.549908)
			(end 1.050036 0.762)
			(stroke
				(width 0.1524)
				(type default)
			)
			(layer "F.SilkS")
		)
		(fp_line
			(start -1.050036 0.762)
			(end -1.050036 1.549908)
			(stroke
				(width 0.1524)
				(type default)
			)
			(layer "F.SilkS")
		)
		(fp_line
			(start -1.050036 -0.2286)
			(end -1.050036 0.2286)
			(stroke
				(width 0.1524)
				(type default)
			)
			(layer "F.SilkS")
		)
		(fp_line
			(start 1.050036 -0.762)
			(end 1.050036 -1.549908)
			(stroke
				(width 0.1524)
				(type default)
			)
			(layer "F.SilkS")
		)
		(fp_line
			(start -1.050036 -1.549908)
			(end -1.050036 -0.762)
			(stroke
				(width 0.1524)
				(type default)
			)
			(layer "F.SilkS")
		)
		(fp_line
			(start -1.016 -1.549908)
			(end -1.050036 -1.549908)
			(stroke
				(width 0.1524)
				(type default)
			)
			(layer "F.SilkS")
		)
		(fp_line
			(start 1.050036 -1.549908)
			(end 1.016 -1.549908)
			(stroke
				(width 0.1524)
				(type default)
			)
			(layer "F.SilkS")
		)
		(fp_poly
			(pts
				(xy -1.851914 -0.720344) (xy -1.411224 -0.499872) (xy -1.851914 -0.279654)
			)
			(stroke
				(width 0)
				(type default)
			)
			(fill yes)
			(layer "F.SilkS")
		)
		(fp_line
			(start -1.050036 1.549908)
			(end 1.050036 1.549908)
			(stroke
				(width 0.1)
				(type default)
			)
			(layer "F.Fab")
		)
		(fp_line
			(start 1.050036 1.549908)
			(end 1.050036 -1.549908)
			(stroke
				(width 0.1)
				(type default)
			)
			(layer "F.Fab")
		)
		(fp_line
			(start -1.050036 -1.549908)
			(end -1.050036 1.549908)
			(stroke
				(width 0.1)
				(type default)
			)
			(layer "F.Fab")
		)
		(fp_line
			(start 1.050036 -1.549908)
			(end -1.050036 -1.549908)
			(stroke
				(width 0.1)
				(type default)
			)
			(layer "F.Fab")
		)
		(fp_poly
			(pts
				(xy -1.851914 -0.720344) (xy -1.411224 -0.499872) (xy -1.851914 -0.279654)
			)
			(stroke
				(width 0)
				(type default)
			)
			(fill yes)
			(layer "F.Fab")
		)
		(pad "1" smd rect
			(at -0.54991 -0.499872)
			(size 0.254 1.4986)
			(layers "F.Cu" "F.Mask" "F.Paste")
			(net "SW_P1V2_AUX_FLT")
		)
		(pad "2" smd rect
			(at -0.54991 0.499872)
			(size 0.254 1.4986)
			(layers "F.Cu" "F.Mask" "F.Paste")
			(net "GND")
		)
		(pad "3" smd rect
			(at -0.750062 1.450086 270)
			(size 0.254 0.7112)
			(layers "F.Cu" "F.Mask" "F.Paste")
			(net "GND")
		)
		(pad "4" smd rect
			(at -0.249936 1.450086 270)
			(size 0.254 0.7112)
			(layers "F.Cu" "F.Mask" "F.Paste")
			(net "GND")
		)
		(pad "5" smd rect
			(at 0.249936 1.450086 270)
			(size 0.254 0.7112)
			(layers "F.Cu" "F.Mask" "F.Paste")
			(net "EN_P1V2_AUX_R")
		)
		(pad "6" smd rect
			(at 0.750062 1.450086 270)
			(size 0.254 0.7112)
			(layers "F.Cu" "F.Mask" "F.Paste")
			(net "P1V2_AUX_VCC")
		)
		(pad "7" smd rect
			(at 0.94996 0.499872)
			(size 0.254 0.7112)
			(layers "F.Cu" "F.Mask" "F.Paste")
			(net "P1V2_AUX_MODE")
		)
		(pad "8" smd rect
			(at 0.54991 0)
			(size 0.254 1.4986)
			(layers "F.Cu" "F.Mask" "F.Paste")
			(net "SW_P1V2_AUX_SW")
		)
		(pad "9" smd rect
			(at 0.94996 -0.499872)
			(size 0.254 0.7112)
			(layers "F.Cu" "F.Mask" "F.Paste")
			(net "SW_P1V2_AUX_BST")
		)
		(pad "10" smd rect
			(at 0.750062 -1.450086 270)
			(size 0.254 0.7112)
			(layers "F.Cu" "F.Mask" "F.Paste")
			(net "P1V2_AUX_VCC")
		)
		(pad "11" smd rect
			(at 0.249936 -1.450086 270)
			(size 0.254 0.7112)
			(layers "F.Cu" "F.Mask" "F.Paste")
			(net "GND")
		)
		(pad "12" smd rect
			(at -0.249936 -1.450086 270)
			(size 0.254 0.7112)
			(layers "F.Cu" "F.Mask" "F.Paste")
			(net "P1V2_AUX")
		)
		(pad "13" smd rect
			(at -0.750062 -1.450086 270)
			(size 0.254 0.7112)
			(layers "F.Cu" "F.Mask" "F.Paste")
			(net "PWRGD_P1V2_AUX_R")
		)
	)
)
